# S9S_MB_2U (Grand Teton) — schematic netlist excerpt (pin names and nets, part order shuffled) for the footprints in the layout excerpt that follows; sources: Cadence DE-HDL packaged netlist, KiCad conversion of 03242023_DA0F0TMBIJ0_F0T_Motherboard_J_brd_V01_OCP.brd

L10  Q_INDUCTOR  BLM18PG121SN1D/2000MA EMPTY  pkg SMLF  page 189 : \1\ = P1V8_PCH_AUX ; \2\ = P1V8_PCH_PLL_AUX
C95  Q_CAP  10UF 16V 10% X6S  pkg C0805  page 106 : A = P12V_S3_AUX_CPU1_NVDIMM ; B = GND

(kicad_pcb
	(version 20260206)
	(generator "pcbnew")
	(generator_version "10.0")
	(general
		(thickness 1.6)
		(legacy_teardrops no)
	)
	(paper "A4")
	(title_block
		(title "03242023_DA0F0TMBIJ0_F0T_Motherboard_J_brd_V01_OCP.brd")
		(comment 1 "Grand Teton / footprints 5753-5754 of 6105")
	)
	(layers
		(0 "F.Cu" signal "TOP")
		(4 "In1.Cu" signal "GND")
		(6 "In2.Cu" signal "IN1")
		(8 "In3.Cu" signal "GND1")
		(10 "In4.Cu" signal "IN2")
		(12 "In5.Cu" signal "GND2")
		(14 "In6.Cu" signal "IN3")
		(16 "In7.Cu" signal "GND3")
		(18 "In8.Cu" signal "VCC")
		(20 "In9.Cu" signal "VCC1")
		(22 "In10.Cu" signal "GND4")
		(24 "In11.Cu" signal "IN4")
		(26 "In12.Cu" signal "GND5")
		(28 "In13.Cu" signal "IN5")
		(30 "In14.Cu" signal "GND6")
		(32 "In15.Cu" signal "IN6")
		(34 "In16.Cu" signal "GND7")
		(2 "B.Cu" signal "BOTTOM")
		(9 "F.Adhes" user "F.Adhesive")
		(11 "B.Adhes" user "B.Adhesive")
		(13 "F.Paste" user "Package Geometry/Pastemask Top")
		(15 "B.Paste" user "Package Geometry/Pastemask Bottom")
		(5 "F.SilkS" user "Ref Des/Silkscreen Top")
		(7 "B.SilkS" user "Ref Des/Silkscreen Bottom")
		(1 "F.Mask" user "Board Geometry/Soldermask Top")
		(3 "B.Mask" user "Board Geometry/Soldermask Bottom")
		(17 "Dwgs.User" user "User.Drawings")
		(19 "Cmts.User" user "User.Comments")
		(21 "Eco1.User" user "User.Eco1")
		(23 "Eco2.User" user "User.Eco2")
		(25 "Edge.Cuts" user "Board Geometry/Outline")
		(27 "Margin" user)
		(31 "F.CrtYd" user "Package Geometry/Place Bound Top")
		(29 "B.CrtYd" user "Package Geometry/Place Bound Bottom")
		(35 "F.Fab" user "Ref Des/Assembly Top")
		(33 "B.Fab" user "Ref Des/Assembly Bottom")
	)
	(footprint ""
		(layer "B.Cu")
		(at 353.0219 -58.458608)
		(property "Reference" "L10"
			(at 0 0 0)
			(layer "B.SilkS")
			(hide yes)
			(effects
				(font
					(size 1.27 1.27)
				)
				(justify mirror)
			)
		)
		(property "Value" ""
			(at 0 0 0)
			(layer "B.Fab")
			(effects
				(font
					(size 1.27 1.27)
				)
				(justify mirror)
			)
		)
		(duplicate_pad_numbers_are_jumpers no)
		(fp_line
			(start -1.27 0.5842)
			(end -1.27 -0.5842)
			(stroke
				(width 0.1524)
				(type default)
			)
			(layer "B.SilkS")
		)
		(fp_line
			(start -1.27 0.5842)
			(end 1.27 0.5842)
			(stroke
				(width 0.1524)
				(type default)
			)
			(layer "B.SilkS")
		)
		(fp_line
			(start -0.127 0.5842)
			(end -0.127 -0.5842)
			(stroke
				(width 0.1524)
				(type default)
			)
			(layer "B.SilkS")
		)
		(fp_line
			(start 0.127 0.5842)
			(end 0.127 -0.5842)
			(stroke
				(width 0.1524)
				(type default)
			)
			(layer "B.SilkS")
		)
		(fp_line
			(start 1.27 -0.5842)
			(end -1.27 -0.5842)
			(stroke
				(width 0.1524)
				(type default)
			)
			(layer "B.SilkS")
		)
		(fp_line
			(start 1.27 -0.5588)
			(end 1.27 -0.5842)
			(stroke
				(width 0.1524)
				(type default)
			)
			(layer "B.SilkS")
		)
		(fp_line
			(start 1.27 0.5842)
			(end 1.27 -0.5842)
			(stroke
				(width 0.1524)
				(type default)
			)
			(layer "B.SilkS")
		)
		(fp_line
			(start -1.1938 -0.406654)
			(end -1.1938 0.4064)
			(stroke
				(width 0.1)
				(type default)
			)
			(layer "B.Fab")
		)
		(fp_line
			(start -1.1938 0.4064)
			(end -0.9144 0.4064)
			(stroke
				(width 0.1)
				(type default)
			)
			(layer "B.Fab")
		)
		(fp_line
			(start -0.9144 -0.508)
			(end -0.9144 -0.406654)
			(stroke
				(width 0.1)
				(type default)
			)
			(layer "B.Fab")
		)
		(fp_line
			(start -0.9144 -0.406654)
			(end -1.1938 -0.406654)
			(stroke
				(width 0.1)
				(type default)
			)
			(layer "B.Fab")
		)
		(fp_line
			(start -0.9144 0.4064)
			(end -0.9144 0.508)
			(stroke
				(width 0.1)
				(type default)
			)
			(layer "B.Fab")
		)
		(fp_line
			(start -0.9144 0.508)
			(end 0.9144 0.508)
			(stroke
				(width 0.1)
				(type default)
			)
			(layer "B.Fab")
		)
		(fp_line
			(start 0.9144 -0.508)
			(end -0.9144 -0.508)
			(stroke
				(width 0.1)
				(type default)
			)
			(layer "B.Fab")
		)
		(fp_line
			(start 0.9144 -0.406654)
			(end 0.9144 -0.508)
			(stroke
				(width 0.1)
				(type default)
			)
			(layer "B.Fab")
		)
		(fp_line
			(start 0.9144 0.406654)
			(end 1.194308 0.406654)
			(stroke
				(width 0.1)
				(type default)
			)
			(layer "B.Fab")
		)
		(fp_line
			(start 0.9144 0.508)
			(end 0.9144 0.406654)
			(stroke
				(width 0.1)
				(type default)
			)
			(layer "B.Fab")
		)
		(fp_line
			(start 1.194308 -0.406654)
			(end 0.9144 -0.406654)
			(stroke
				(width 0.1)
				(type default)
			)
			(layer "B.Fab")
		)
		(fp_line
			(start 1.194308 0.406654)
			(end 1.194308 -0.406654)
			(stroke
				(width 0.1)
				(type default)
			)
			(layer "B.Fab")
		)
		(pad "1" smd rect
			(at 0.7366 0 270)
			(size 0.7112 0.8128)
			(layers "B.Cu" "B.Mask" "B.Paste")
			(net "P1V8_PCH_AUX")
		)
		(pad "2" smd rect
			(at -0.7366 0 270)
			(size 0.7112 0.8128)
			(layers "B.Cu" "B.Mask" "B.Paste")
			(net "P1V8_PCH_PLL_AUX")
		)
	)
	(footprint ""
		(layer "B.Cu")
		(at 170.433746 -321.554856 -90)
		(property "Reference" "C95"
			(at 0 0 90)
			(layer "B.SilkS")
			(hide yes)
			(effects
				(font
					(size 1.27 1.27)
				)
				(justify mirror)
			)
		)
		(property "Value" ""
			(at 0 0 90)
			(layer "B.Fab")
			(effects
				(font
					(size 1.27 1.27)
				)
				(justify mirror)
			)
		)
		(duplicate_pad_numbers_are_jumpers no)
		(fp_line
			(start -1.524 0.762)
			(end 1.524 0.762)
			(stroke
				(width 0.1524)
				(type default)
			)
			(layer "B.SilkS")
		)
		(fp_line
			(start 1.524 0.762)
			(end 1.524 -0.762)
			(stroke
				(width 0.1524)
				(type default)
			)
			(layer "B.SilkS")
		)
		(fp_line
			(start -1.524 -0.762)
			(end -1.524 0.762)
			(stroke
				(width 0.1524)
				(type default)
			)
			(layer "B.SilkS")
		)
		(fp_line
			(start 1.524 -0.762)
			(end -1.524 -0.762)
			(stroke
				(width 0.1524)
				(type default)
			)
			(layer "B.SilkS")
		)
		(fp_line
			(start -1.1049 0.724916)
			(end -1.1049 -0.724916)
			(stroke
				(width 0.1)
				(type default)
			)
			(layer "B.Fab")
		)
		(fp_line
			(start 1.1049 0.724916)
			(end -1.1049 0.724916)
			(stroke
				(width 0.1)
				(type default)
			)
			(layer "B.Fab")
		)
		(fp_line
			(start -1.1049 -0.724916)
			(end 1.1049 -0.724916)
			(stroke
				(width 0.1)
				(type default)
			)
			(layer "B.Fab")
		)
		(fp_line
			(start 1.1049 -0.724916)
			(end 1.1049 0.724916)
			(stroke
				(width 0.1)
				(type default)
			)
			(layer "B.Fab")
		)
		(pad "1" smd rect
			(at 0.889 0 270)
			(size 1.016 1.27)
			(layers "B.Cu" "B.Mask" "B.Paste")
			(net "P12V_S3_AUX_CPU1_NVDIMM")
		)
		(pad "2" smd rect
			(at -0.889 0 270)
			(size 1.016 1.27)
			(layers "B.Cu" "B.Mask" "B.Paste")
			(net "GND")
		)
	)
)
